(kicad_pcb
	(version 20260206)
	(generator "pcbnew")
	(generator_version "10.0")
	(general
		(thickness 1.6)
		(legacy_teardrops no)
	)
	(paper "A4")
	(title_block
		(title "01162023_DA0F0TEBIF0_F0T_Expander_BD_F_brd_V02_OCP.brd")
		(comment 1 "Grand Teton / footprints 3945-3949 of 9728")
	)
	(layers
		(0 "F.Cu" signal "TOP")
		(4 "In1.Cu" signal "GND")
		(6 "In2.Cu" signal "VCC")
		(8 "In3.Cu" signal "VCC1")
		(10 "In4.Cu" signal "GND1")
		(12 "In5.Cu" signal "IN1")
		(14 "In6.Cu" signal "GND2")
		(16 "In7.Cu" signal "IN2")
		(18 "In8.Cu" signal "GND3")
		(20 "In9.Cu" signal "IN3")
		(22 "In10.Cu" signal "GND4")
		(24 "In11.Cu" signal "IN4")
		(26 "In12.Cu" signal "GND5")
		(28 "In13.Cu" signal "IN5")
		(30 "In14.Cu" signal "GND6")
		(32 "In15.Cu" signal "IN6")
		(34 "In16.Cu" signal "GND7")
		(2 "B.Cu" signal "BOTTOM")
		(9 "F.Adhes" user "F.Adhesive")
		(11 "B.Adhes" user "B.Adhesive")
		(13 "F.Paste" user "Package Geometry/Pastemask Top")
		(15 "B.Paste" user "Package Geometry/Pastemask Bottom")
		(5 "F.SilkS" user "Ref Des/Silkscreen Top")
		(7 "B.SilkS" user "Ref Des/Silkscreen Bottom")
		(1 "F.Mask" user "Board Geometry/Soldermask Top")
		(3 "B.Mask" user "Board Geometry/Soldermask Bottom")
		(17 "Dwgs.User" user "User.Drawings")
		(19 "Cmts.User" user "User.Comments")
		(21 "Eco1.User" user "User.Eco1")
		(23 "Eco2.User" user "User.Eco2")
		(25 "Edge.Cuts" user "Board Geometry/Outline")
		(27 "Margin" user)
		(31 "F.CrtYd" user "Package Geometry/Place Bound Top")
		(29 "B.CrtYd" user "Package Geometry/Place Bound Bottom")
		(35 "F.Fab" user "Ref Des/Assembly Top")
		(33 "B.Fab" user "Ref Des/Assembly Bottom")
	)
	(footprint ""
		(layer "F.Cu")
		(at 258.78409 -29.222954 -90)
		(property "Reference" "PC958"
			(at 0 0 270)
			(layer "F.SilkS")
			(hide yes)
			(effects
				(font
					(size 1.27 1.27)
				)
			)
		)
		(property "Value" ""
			(at 0 0 270)
			(layer "F.Fab")
			(effects
				(font
					(size 1.27 1.27)
				)
			)
		)
		(duplicate_pad_numbers_are_jumpers no)
		(fp_line
			(start -0.7874 0.4064)
			(end -0.7874 -0.4064)
			(stroke
				(width 0.1524)
				(type default)
			)
			(layer "F.SilkS")
		)
		(fp_line
			(start 0.7874 0.4064)
			(end -0.7874 0.4064)
			(stroke
				(width 0.1524)
				(type default)
			)
			(layer "F.SilkS")
		)
		(fp_line
			(start -0.7874 -0.4064)
			(end 0.7874 -0.4064)
			(stroke
				(width 0.1524)
				(type default)
			)
			(layer "F.SilkS")
		)
		(fp_line
			(start 0.7874 -0.4064)
			(end 0.7874 0.4064)
			(stroke
				(width 0.1524)
				(type default)
			)
			(layer "F.SilkS")
		)
		(fp_line
			(start -0.67945 0.3048)
			(end -0.67945 -0.305054)
			(stroke
				(width 0.1)
				(type default)
			)
			(layer "F.Fab")
		)
		(fp_line
			(start -0.12065 0.3048)
			(end -0.67945 0.3048)
			(stroke
				(width 0.1)
				(type default)
			)
			(layer "F.Fab")
		)
		(fp_line
			(start 0.120396 0.3048)
			(end 0.120396 0.2794)
			(stroke
				(width 0.1)
				(type default)
			)
			(layer "F.Fab")
		)
		(fp_line
			(start 0.67945 0.3048)
			(end 0.120396 0.3048)
			(stroke
				(width 0.1)
				(type default)
			)
			(layer "F.Fab")
		)
		(fp_line
			(start -0.12065 0.2794)
			(end -0.12065 0.3048)
			(stroke
				(width 0.1)
				(type default)
			)
			(layer "F.Fab")
		)
		(fp_line
			(start 0.120396 0.2794)
			(end -0.12065 0.2794)
			(stroke
				(width 0.1)
				(type default)
			)
			(layer "F.Fab")
		)
		(fp_line
			(start -0.12065 -0.2794)
			(end 0.12065 -0.2794)
			(stroke
				(width 0.1)
				(type default)
			)
			(layer "F.Fab")
		)
		(fp_line
			(start 0.12065 -0.2794)
			(end 0.12065 -0.3048)
			(stroke
				(width 0.1)
				(type default)
			)
			(layer "F.Fab")
		)
		(fp_line
			(start 0.12065 -0.3048)
			(end 0.67945 -0.3048)
			(stroke
				(width 0.1)
				(type default)
			)
			(layer "F.Fab")
		)
		(fp_line
			(start 0.67945 -0.3048)
			(end 0.67945 0.3048)
			(stroke
				(width 0.1)
				(type default)
			)
			(layer "F.Fab")
		)
		(fp_line
			(start -0.67945 -0.305054)
			(end -0.12065 -0.305054)
			(stroke
				(width 0.1)
				(type default)
			)
			(layer "F.Fab")
		)
		(fp_line
			(start -0.12065 -0.305054)
			(end -0.12065 -0.2794)
			(stroke
				(width 0.1)
				(type default)
			)
			(layer "F.Fab")
		)
		(pad "1" smd circle
			(at -0.40005 0 270)
			(size 0 0)
			(layers "F.Cu" "F.Mask" "F.Paste")
			(net "P3V3_AUX")
		)
		(pad "2" smd circle
			(at 0.40005 0 270)
			(size 0 0)
			(layers "F.Cu" "F.Mask" "F.Paste")
			(net "GND")
		)
	)
	(footprint ""
		(layer "F.Cu")
		(at 188.546486 -58.323734)
		(property "Reference" "PC389"
			(at 0 0 0)
			(layer "F.SilkS")
			(hide yes)
			(effects
				(font
					(size 1.27 1.27)
				)
			)
		)
		(property "Value" ""
			(at 0 0 0)
			(layer "F.Fab")
			(effects
				(font
					(size 1.27 1.27)
				)
			)
		)
		(duplicate_pad_numbers_are_jumpers no)
		(fp_line
			(start -1.524 -0.762)
			(end 1.524 -0.762)
			(stroke
				(width 0.1524)
				(type default)
			)
			(layer "F.SilkS")
		)
		(fp_line
			(start -1.524 0.762)
			(end -1.524 -0.762)
			(stroke
				(width 0.1524)
				(type default)
			)
			(layer "F.SilkS")
		)
		(fp_line
			(start 1.524 -0.762)
			(end 1.524 0.762)
			(stroke
				(width 0.1524)
				(type default)
			)
			(layer "F.SilkS")
		)
		(fp_line
			(start 1.524 0.762)
			(end -1.524 0.762)
			(stroke
				(width 0.1524)
				(type default)
			)
			(layer "F.SilkS")
		)
		(fp_line
			(start -1.1049 -0.724916)
			(end -1.1049 0.724916)
			(stroke
				(width 0.1)
				(type default)
			)
			(layer "F.Fab")
		)
		(fp_line
			(start -1.1049 0.724916)
			(end 1.1049 0.724916)
			(stroke
				(width 0.1)
				(type default)
			)
			(layer "F.Fab")
		)
		(fp_line
			(start 1.1049 -0.724916)
			(end -1.1049 -0.724916)
			(stroke
				(width 0.1)
				(type default)
			)
			(layer "F.Fab")
		)
		(fp_line
			(start 1.1049 0.724916)
			(end 1.1049 -0.724916)
			(stroke
				(width 0.1)
				(type default)
			)
			(layer "F.Fab")
		)
		(pad "1" smd rect
			(at -0.889 0 180)
			(size 1.016 1.27)
			(layers "F.Cu" "F.Mask" "F.Paste")
			(net "GND")
		)
		(pad "2" smd rect
			(at 0.889 0 180)
			(size 1.016 1.27)
			(layers "F.Cu" "F.Mask" "F.Paste")
			(net "P12V_AUX")
		)
	)
	(footprint ""
		(layer "F.Cu")
		(at 381.786384 -250.070874 -90)
		(property "Reference" "R1402"
			(at 0 0 270)
			(layer "F.SilkS")
			(hide yes)
			(effects
				(font
					(size 1.27 1.27)
				)
			)
		)
		(property "Value" ""
			(at 0 0 270)
			(layer "F.Fab")
			(effects
				(font
					(size 1.27 1.27)
				)
			)
		)
		(duplicate_pad_numbers_are_jumpers no)
		(fp_line
			(start -0.7874 0.4064)
			(end -0.7874 -0.4064)
			(stroke
				(width 0.1524)
				(type default)
			)
			(layer "F.SilkS")
		)
		(fp_line
			(start 0.7874 0.4064)
			(end -0.7874 0.4064)
			(stroke
				(width 0.1524)
				(type default)
			)
			(layer "F.SilkS")
		)
		(fp_line
			(start -0.7874 -0.4064)
			(end 0.7874 -0.4064)
			(stroke
				(width 0.1524)
				(type default)
			)
			(layer "F.SilkS")
		)
		(fp_line
			(start 0.7874 -0.4064)
			(end 0.7874 0.4064)
			(stroke
				(width 0.1524)
				(type default)
			)
			(layer "F.SilkS")
		)
		(fp_line
			(start -0.67945 0.3048)
			(end -0.67945 -0.305054)
			(stroke
				(width 0.1)
				(type default)
			)
			(layer "F.Fab")
		)
		(fp_line
			(start -0.12065 0.3048)
			(end -0.67945 0.3048)
			(stroke
				(width 0.1)
				(type default)
			)
			(layer "F.Fab")
		)
		(fp_line
			(start 0.120396 0.3048)
			(end 0.120396 0.2794)
			(stroke
				(width 0.1)
				(type default)
			)
			(layer "F.Fab")
		)
		(fp_line
			(start 0.67945 0.3048)
			(end 0.120396 0.3048)
			(stroke
				(width 0.1)
				(type default)
			)
			(layer "F.Fab")
		)
		(fp_line
			(start -0.12065 0.2794)
			(end -0.12065 0.3048)
			(stroke
				(width 0.1)
				(type default)
			)
			(layer "F.Fab")
		)
		(fp_line
			(start 0.120396 0.2794)
			(end -0.12065 0.2794)
			(stroke
				(width 0.1)
				(type default)
			)
			(layer "F.Fab")
		)
		(fp_line
			(start -0.12065 -0.2794)
			(end 0.12065 -0.2794)
			(stroke
				(width 0.1)
				(type default)
			)
			(layer "F.Fab")
		)
		(fp_line
			(start 0.12065 -0.2794)
			(end 0.12065 -0.3048)
			(stroke
				(width 0.1)
				(type default)
			)
			(layer "F.Fab")
		)
		(fp_line
			(start 0.12065 -0.3048)
			(end 0.67945 -0.3048)
			(stroke
				(width 0.1)
				(type default)
			)
			(layer "F.Fab")
		)
		(fp_line
			(start 0.67945 -0.3048)
			(end 0.67945 0.3048)
			(stroke
				(width 0.1)
				(type default)
			)
			(layer "F.Fab")
		)
		(fp_line
			(start -0.67945 -0.305054)
			(end -0.12065 -0.305054)
			(stroke
				(width 0.1)
				(type default)
			)
			(layer "F.Fab")
		)
		(fp_line
			(start -0.12065 -0.305054)
			(end -0.12065 -0.2794)
			(stroke
				(width 0.1)
				(type default)
			)
			(layer "F.Fab")
		)
		(pad "1" smd circle
			(at -0.40005 0 270)
			(size 0 0)
			(layers "F.Cu" "F.Mask" "F.Paste")
			(net "PEX3_DBG_MODE2")
		)
		(pad "2" smd circle
			(at 0.40005 0 270)
			(size 0 0)
			(layers "F.Cu" "F.Mask" "F.Paste")
			(net "P1V8_PEX")
		)
	)
	(footprint ""
		(layer "F.Cu")
		(at 199.394064 -34.248852)
		(property "Reference" "R5672"
			(at 0 0 0)
			(layer "F.SilkS")
			(hide yes)
			(effects
				(font
					(size 1.27 1.27)
				)
			)
		)
		(property "Value" ""
			(at 0 0 0)
			(layer "F.Fab")
			(effects
				(font
					(size 1.27 1.27)
				)
			)
		)
		(duplicate_pad_numbers_are_jumpers no)
		(fp_line
			(start -0.7874 -0.4064)
			(end 0.7874 -0.4064)
			(stroke
				(width 0.1524)
				(type default)
			)
			(layer "F.SilkS")
		)
		(fp_line
			(start -0.7874 0.4064)
			(end -0.7874 -0.4064)
			(stroke
				(width 0.1524)
				(type default)
			)
			(layer "F.SilkS")
		)
		(fp_line
			(start 0.7874 -0.4064)
			(end 0.7874 0.4064)
			(stroke
				(width 0.1524)
				(type default)
			)
			(layer "F.SilkS")
		)
		(fp_line
			(start 0.7874 0.4064)
			(end -0.7874 0.4064)
			(stroke
				(width 0.1524)
				(type default)
			)
			(layer "F.SilkS")
		)
		(fp_line
			(start -0.67945 -0.305054)
			(end -0.12065 -0.305054)
			(stroke
				(width 0.1)
				(type default)
			)
			(layer "F.Fab")
		)
		(fp_line
			(start -0.67945 0.3048)
			(end -0.67945 -0.305054)
			(stroke
				(width 0.1)
				(type default)
			)
			(layer "F.Fab")
		)
		(fp_line
			(start -0.12065 -0.305054)
			(end -0.12065 -0.2794)
			(stroke
				(width 0.1)
				(type default)
			)
			(layer "F.Fab")
		)
		(fp_line
			(start -0.12065 -0.2794)
			(end 0.12065 -0.2794)
			(stroke
				(width 0.1)
				(type default)
			)
			(layer "F.Fab")
		)
		(fp_line
			(start -0.12065 0.2794)
			(end -0.12065 0.3048)
			(stroke
				(width 0.1)
				(type default)
			)
			(layer "F.Fab")
		)
		(fp_line
			(start -0.12065 0.3048)
			(end -0.67945 0.3048)
			(stroke
				(width 0.1)
				(type default)
			)
			(layer "F.Fab")
		)
		(fp_line
			(start 0.120396 0.2794)
			(end -0.12065 0.2794)
			(stroke
				(width 0.1)
				(type default)
			)
			(layer "F.Fab")
		)
		(fp_line
			(start 0.120396 0.3048)
			(end 0.120396 0.2794)
			(stroke
				(width 0.1)
				(type default)
			)
			(layer "F.Fab")
		)
		(fp_line
			(start 0.12065 -0.3048)
			(end 0.67945 -0.3048)
			(stroke
				(width 0.1)
				(type default)
			)
			(layer "F.Fab")
		)
		(fp_line
			(start 0.12065 -0.2794)
			(end 0.12065 -0.3048)
			(stroke
				(width 0.1)
				(type default)
			)
			(layer "F.Fab")
		)
		(fp_line
			(start 0.67945 -0.3048)
			(end 0.67945 0.3048)
			(stroke
				(width 0.1)
				(type default)
			)
			(layer "F.Fab")
		)
		(fp_line
			(start 0.67945 0.3048)
			(end 0.120396 0.3048)
			(stroke
				(width 0.1)
				(type default)
			)
			(layer "F.Fab")
		)
		(pad "1" smd circle
			(at -0.40005 0)
			(size 0 0)
			(layers "F.Cu" "F.Mask" "F.Paste")
			(net "RST_SMB_SSD7_ISO_N")
		)
		(pad "2" smd circle
			(at 0.40005 0)
			(size 0 0)
			(layers "F.Cu" "F.Mask" "F.Paste")
			(net "P3V3_SSD7")
		)
	)
	(footprint ""
		(layer "F.Cu")
		(at 102.626922 -245.339616 -90)
		(property "Reference" "R822"
			(at 0 0 270)
			(layer "F.SilkS")
			(hide yes)
			(effects
				(font
					(size 1.27 1.27)
				)
			)
		)
		(property "Value" ""
			(at 0 0 270)
			(layer "F.Fab")
			(effects
				(font
					(size 1.27 1.27)
				)
			)
		)
		(duplicate_pad_numbers_are_jumpers no)
		(fp_line
			(start -0.7874 0.4064)
			(end -0.7874 -0.4064)
			(stroke
				(width 0.1524)
				(type default)
			)
			(layer "F.SilkS")
		)
		(fp_line
			(start 0.7874 0.4064)
			(end -0.7874 0.4064)
			(stroke
				(width 0.1524)
				(type default)
			)
			(layer "F.SilkS")
		)
		(fp_line
			(start -0.7874 -0.4064)
			(end 0.7874 -0.4064)
			(stroke
				(width 0.1524)
				(type default)
			)
			(layer "F.SilkS")
		)
		(fp_line
			(start 0.7874 -0.4064)
			(end 0.7874 0.4064)
			(stroke
				(width 0.1524)
				(type default)
			)
			(layer "F.SilkS")
		)
		(fp_line
			(start -0.67945 0.3048)
			(end -0.67945 -0.305054)
			(stroke
				(width 0.1)
				(type default)
			)
			(layer "F.Fab")
		)
		(fp_line
			(start -0.12065 0.3048)
			(end -0.67945 0.3048)
			(stroke
				(width 0.1)
				(type default)
			)
			(layer "F.Fab")
		)
		(fp_line
			(start 0.120396 0.3048)
			(end 0.120396 0.2794)
			(stroke
				(width 0.1)
				(type default)
			)
			(layer "F.Fab")
		)
		(fp_line
			(start 0.67945 0.3048)
			(end 0.120396 0.3048)
			(stroke
				(width 0.1)
				(type default)
			)
			(layer "F.Fab")
		)
		(fp_line
			(start -0.12065 0.2794)
			(end -0.12065 0.3048)
			(stroke
				(width 0.1)
				(type default)
			)
			(layer "F.Fab")
		)
		(fp_line
			(start 0.120396 0.2794)
			(end -0.12065 0.2794)
			(stroke
				(width 0.1)
				(type default)
			)
			(layer "F.Fab")
		)
		(fp_line
			(start -0.12065 -0.2794)
			(end 0.12065 -0.2794)
			(stroke
				(width 0.1)
				(type default)
			)
			(layer "F.Fab")
		)
		(fp_line
			(start 0.12065 -0.2794)
			(end 0.12065 -0.3048)
			(stroke
				(width 0.1)
				(type default)
			)
			(layer "F.Fab")
		)
		(fp_line
			(start 0.12065 -0.3048)
			(end 0.67945 -0.3048)
			(stroke
				(width 0.1)
				(type default)
			)
			(layer "F.Fab")
		)
		(fp_line
			(start 0.67945 -0.3048)
			(end 0.67945 0.3048)
			(stroke
				(width 0.1)
				(type default)
			)
			(layer "F.Fab")
		)
		(fp_line
			(start -0.67945 -0.305054)
			(end -0.12065 -0.305054)
			(stroke
				(width 0.1)
				(type default)
			)
			(layer "F.Fab")
		)
		(fp_line
			(start -0.12065 -0.305054)
			(end -0.12065 -0.2794)
			(stroke
				(width 0.1)
				(type default)
			)
			(layer "F.Fab")
		)
		(pad "1" smd circle
			(at -0.40005 0 270)
			(size 0 0)
			(layers "F.Cu" "F.Mask" "F.Paste")
			(net "P1V8_PEX")
		)
		(pad "2" smd circle
			(at 0.40005 0 270)
			(size 0 0)
			(layers "F.Cu" "F.Mask" "F.Paste")
			(net "P12V_PEX_P1V8_VIN_N")
		)
	)
)
